# BASEBOARD_FAB2 (Tioga Pass) — schematic parts with pin connectivity, parts 2386–2391 of 4751; source: Cadence DE-HDL packaged netlist (pstxprt.dat, pstxnet.dat, pstchip.dat)

J8E3  SCONN80_E67482007  CONN  pkg SM  page 187
  1  IO1  BI  = FM_MEZZB_PRSNT1_N
  2  IO2  BI  = P12V_STBY
  3  IO3  BI  = GND
  4  IO4  BI  = P12V_STBY
  5  IO5  BI  = P3E_CPU0_PE3_OCP_RXP<7>
  6  IO6  BI  = TP_RSVD_B1
  7  IO7  BI  = P3E_CPU0_PE3_OCP_RXN<7>
  8  IO8  BI  = GND
  9  IO9  BI  = GND
  10  IO10  BI  = P3E_OCP_CPU0_PE3_C_TXP<7>
  11  IO11  BI  = GND
  12  IO12  BI  = P3E_OCP_CPU0_PE3_C_TXN<7>
  13  IO13  BI  = P3E_CPU0_PE3_OCP_RXN<6>
  14  IO14  BI  = GND
  15  IO15  BI  = P3E_CPU0_PE3_OCP_RXP<6>
  16  IO16  BI  = GND
  17  IO17  BI  = GND
  18  IO18  BI  = P3E_OCP_CPU0_PE3_C_TXP<6>
  19  IO19  BI  = GND
  20  IO20  BI  = P3E_OCP_CPU0_PE3_C_TXN<6>
  21  IO21  BI  = P3E_CPU0_PE3_OCP_RXN<5>
  22  IO22  BI  = GND
  23  IO23  BI  = P3E_CPU0_PE3_OCP_RXP<5>
  24  IO24  BI  = GND
  25  IO25  BI  = GND
  26  IO26  BI  = P3E_OCP_CPU0_PE3_C_TXP<5>
  27  IO27  BI  = GND
  28  IO28  BI  = P3E_OCP_CPU0_PE3_C_TXN<5>
  29  IO29  BI  = P3E_CPU0_PE3_OCP_RXN<4>
  30  IO30  BI  = GND
  31  IO31  BI  = P3E_CPU0_PE3_OCP_RXP<4>
  32  IO32  BI  = GND
  33  IO33  BI  = GND
  34  IO34  BI  = P3E_OCP_CPU0_PE3_C_TXP<4>
  35  IO35  BI  = GND
  36  IO36  BI  = P3E_OCP_CPU0_PE3_C_TXN<4>
  37  IO37  BI  = P3E_CPU0_PE3_OCP_RXP<3>
  38  IO38  BI  = GND
  39  IO39  BI  = P3E_CPU0_PE3_OCP_RXN<3>
  40  IO40  BI  = GND
  41  IO41  BI  = GND
  42  IO42  BI  = P3E_OCP_CPU0_PE3_C_TXP<3>
  43  IO43  BI  = GND
  44  IO44  BI  = P3E_OCP_CPU0_PE3_C_TXN<3>
  45  IO45  BI  = P3E_CPU0_PE3_OCP_RXP<2>
  46  IO46  BI  = GND
  47  IO47  BI  = P3E_CPU0_PE3_OCP_RXN<2>
  48  IO48  BI  = GND
  49  IO49  BI  = GND
  50  IO50  BI  = P3E_OCP_CPU0_PE3_C_TXP<2>
  51  IO51  BI  = GND
  52  IO52  BI  = P3E_OCP_CPU0_PE3_C_TXN<2>
  53  IO53  BI  = P3E_CPU0_PE3_OCP_RXP<1>
  54  IO54  BI  = GND
  55  IO55  BI  = P3E_CPU0_PE3_OCP_RXN<1>
  56  IO56  BI  = GND
  57  IO57  BI  = GND
  58  IO58  BI  = P3E_OCP_CPU0_PE3_C_TXP<1>
  59  IO59  BI  = GND
  60  IO60  BI  = P3E_OCP_CPU0_PE3_C_TXN<1>
  61  IO61  BI  = P3E_CPU0_PE3_OCP_RXP<0>
  62  IO62  BI  = GND
  63  IO63  BI  = P3E_CPU0_PE3_OCP_RXN<0>
  64  IO64  BI  = GND
  65  IO65  BI  = GND
  66  IO66  BI  = P3E_OCP_CPU0_PE3_C_TXP<0>
  67  IO67  BI  = GND
  68  IO68  BI  = P3E_OCP_CPU0_PE3_C_TXN<0>
  69  IO69  BI  = CLK_100M_MEZZ3_DP
  70  IO70  BI  = GND
  71  IO71  BI  = CLK_100M_MEZZ3_DN
  72  IO72  BI  = GND
  73  IO73  BI  = GND
  74  IO74  BI  = CLK_100M_MEZZ4_DP
  75  IO75  BI  = RST_PCIE_CPU_DEV1_R_N
  76  IO76  BI  = CLK_100M_MEZZ4_DN
  77  IO77  BI  = RST_PCIE_CPU_DEV2_R_N
  78  IO78  BI  = GND
  79  IO79  BI  = RST_PCIE_CPU_DEV3_R_N
  80  IO80  BI  = FM_OCP_MEZZB_PRES_N

J8E4  SCONN64_H87568002_A  CONN  pkg SMT  page 188
  1  IO1  BI  = SMB_OCP_FRU_STBY_LVC3_SCL
  2  IO2  BI  = SMB_OCP_FRU_STBY_LVC3_SDA
  3  IO3  BI  = EXT_MDIO_I2C_SEL
  4  IO4  BI  = GND
  5  IO5  BI  = NC
  6  IO6  BI  = NC
  7  IO7  BI  = GND
  8  IO8  BI  = LED_GBE_P1_0
  9  IO9  BI  = LED_GBE_P1_1
  10  IO10  BI  = GND
  11  IO11  BI  = NC
  12  IO12  BI  = NC
  13  IO13  BI  = GND
  14  IO14  BI  = LED_GBE_P2_0
  15  IO15  BI  = LED_GBE_P2_1
  16  IO16  BI  = GND
  17  IO17  BI  = NC
  18  IO18  BI  = NC
  19  IO19  BI  = GND
  20  IO20  BI  = SMB_PCH_MEZZ_LOM0_SCL
  21  IO21  BI  = SMB_PCH_MEZZ_LOM0_SDA
  22  IO22  BI  = GND
  23  IO23  BI  = NC
  24  IO24  BI  = NC
  25  IO25  BI  = GND
  26  IO26  BI  = SMB_PCH_MEZZ_LOM1_SCL
  27  IO27  BI  = SMB_PCH_MEZZ_LOM1_SDA
  28  IO28  BI  = GND
  29  IO29  BI  = SMB_PCH_MEZZ_LOM3_SCL
  30  IO30  BI  = SMB_PCH_MEZZ_LOM3_SDA
  31  IO31  BI  = FM_GBE2_LVC3_MOD_ABS
  32  IO32  BI  = FM_GBE3_LVC3_MOD_ABS
  33  IO33  BI  = P12V_STBY
  34  IO34  BI  = P12V_STBY
  35  IO35  BI  = P12V_STBY
  36  IO36  BI  = TP_RSVD<0>
  37  IO37  BI  = FM_GBE0_LVC3_MOD_ABS
  38  IO38  BI  = FM_GBE1_LVC3_MOD_ABS
  39  IO39  BI  = GND
  40  IO40  BI  = KR_P0_OCP_TX_DP
  41  IO41  BI  = KR_P0_OCP_TX_DN
  42  IO42  BI  = GND
  43  IO43  BI  = LED_GBE_P0_0
  44  IO44  BI  = LED_GBE_P0_1
  45  IO45  BI  = GND
  46  IO46  BI  = KR_P1_OCP_TX_DP
  47  IO47  BI  = KR_P1_OCP_TX_DN
  48  IO48  BI  = GND
  49  IO49  BI  = TP_SHARED_KR_MDC_0
  50  IO50  BI  = TP_SHARED_KR_MDIO_0
  51  IO51  BI  = GND
  52  IO52  BI  = KR_P0_OCP_RX_DP
  53  IO53  BI  = KR_P0_OCP_RX_DN
  54  IO54  BI  = GND
  55  IO55  BI  = LED_GBE_P3_0
  56  IO56  BI  = LED_GBE_P3_1
  57  IO57  BI  = GND
  58  IO58  BI  = KR_P1_OCP_RX_DP
  59  IO59  BI  = KR_P1_OCP_RX_DN
  60  IO60  BI  = GND
  61  IO61  BI  = SMB_PCH_MEZZ_LOM2_SCL
  62  IO62  BI  = SMB_PCH_MEZZ_LOM2_SDA
  63  IO63  BI  = GND
  64  IO64  BI  = FM_OCP_MEZZC_PRES_N

J8F1  SKT-MINI67P-41-GP  pkg SOCKET-G4  page 185
  1  \1\  UNSPEC  = GND
  2  \2\  UNSPEC  = P3V3
  3  \3\  UNSPEC  = GND
  4  \4\  UNSPEC  = P3V3
  5  \5\  UNSPEC  = P3E_PCH_M2_RX_DN<3>
  6  \6\  UNSPEC  = NC_M2<0>
  7  \7\  UNSPEC  = P3E_PCH_M2_RX_DP<3>
  8  \8\  UNSPEC  = NC_M2<1>
  9  \9\  UNSPEC  = GND
  10  \10\  UNSPEC  = TP_LED_M2_ACT_N
  11  \11\  UNSPEC  = P3E_PCH_M2_TX_C_DN<3>
  12  \12\  UNSPEC  = P3V3
  13  \13\  UNSPEC  = P3E_PCH_M2_TX_C_DP<3>
  14  \14\  UNSPEC  = P3V3
  15  \15\  UNSPEC  = GND
  16  \16\  UNSPEC  = P3V3
  17  \17\  UNSPEC  = P3E_PCH_M2_RX_DN<2>
  18  \18\  UNSPEC  = P3V3
  19  \19\  UNSPEC  = P3E_PCH_M2_RX_DP<2>
  20  \20\  UNSPEC  = NC
  21  \21\  UNSPEC  = GND
  22  \22\  UNSPEC  = NC
  23  \23\  UNSPEC  = P3E_PCH_M2_TX_C_DN<2>
  24  \24\  UNSPEC  = NC
  25  \25\  UNSPEC  = P3E_PCH_M2_TX_C_DP<2>
  26  \26\  UNSPEC  = NC
  27  \27\  UNSPEC  = GND
  28  \28\  UNSPEC  = NC
  29  \29\  UNSPEC  = P3E_PCH_M2_RX_DN<1>
  30  \30\  UNSPEC  = NC
  31  \31\  UNSPEC  = P3E_PCH_M2_RX_DP<1>
  32  \32\  UNSPEC  = NC
  33  \33\  UNSPEC  = GND
  34  \34\  UNSPEC  = NC
  35  \35\  UNSPEC  = P3E_PCH_M2_TX_C_DN<1>
  36  \36\  UNSPEC  = NC
  37  \37\  UNSPEC  = P3E_PCH_M2_TX_C_DP<1>
  38  \38\  UNSPEC  = TP_M2_DEVSLP
  39  \39\  UNSPEC  = GND
  40  \40\  UNSPEC  = SMB_M2_SCL
  41  \41\  UNSPEC  = P3E_PCH_M2_SATA6G_RX_R_DP
  42  \42\  UNSPEC  = SMB_M2_SDA
  43  \43\  UNSPEC  = P3E_PCH_M2_SATA6G_RX_R_DN
  44  \44\  UNSPEC  = SMB_M2_ALT_N
  45  \45\  UNSPEC  = GND
  46  \46\  UNSPEC  = NC
  47  \47\  UNSPEC  = P3E_PCH_M2_SATA6G_TX_R_DN
  48  \48\  UNSPEC  = NC
  49  \49\  UNSPEC  = P3E_PCH_M2_SATA6G_TX_R_DP
  50  \50\  UNSPEC  = RST_PCIE_M2_DEV_IC_N
  51  \51\  UNSPEC  = GND
  52  \52\  UNSPEC  = PU_M2_CLK_REQ_N
  53  \53\  UNSPEC  = CLK_100M_M2_DN
  54  \54\  UNSPEC  = FM_PE_M2_WAKE_N
  55  \55\  UNSPEC  = CLK_100M_M2_DP
  56  \56\  UNSPEC  = NC
  57  \57\  UNSPEC  = GND
  58  \58\  UNSPEC  = NC
  67  \67\  UNSPEC  = NC
  68  \68\  UNSPEC  = TP_M2_32M_SUSCLK
  69  \69\  UNSPEC  = FM_M2_SSD_PEDET
  70  \70\  UNSPEC  = P3V3
  71  \71\  UNSPEC  = GND
  72  \72\  UNSPEC  = P3V3
  73  \73\  UNSPEC  = GND
  74  \74\  UNSPEC  = P3V3
  75  \75\  UNSPEC  = GND
  76  \76\  UNSPEC  = GND
  77  \77\  UNSPEC  = GND
  NP1  NP1  UNSPEC  = NC
  NP2  NP2  UNSPEC  = NC

J8G1  SCONN200_H68296001  CONN  pkg SM  page 108
  1  IO1  BI  = P12V
  2  IO2  BI  = P12V
  3  IO3  BI  = P12V
  4  IO4  BI  = P12V
  5  IO5  BI  = P12V
  6  IO6  BI  = P12V
  7  IO7  BI  = P12V
  8  IO8  BI  = P12V
  9  IO9  BI  = P12V
  10  IO10  BI  = P12V
  11  IO11  BI  = P12V
  12  IO12  BI  = P12V
  13  IO13  BI  = GND
  14  IO14  BI  = GND
  15  IO15  BI  = SMB_SLOTX24_STBY_LVC3_SDA_R2
  16  IO16  BI  = IRQ_OOB_MGMT_RISER_ALERT_N
  17  IO17  BI  = SMB_SLOTX24_STBY_LVC3_SCL_R2
  18  IO18  BI  = FM_SLT_CFG1
  19  IO19  BI  = FM_SLT_CFG0
  20  IO20  BI  = FM_PWRBRK_SLOT_N
  21  IO21  BI  = P3V3
  22  IO22  BI  = P3V3
  23  IO23  BI  = P3V3
  24  IO24  BI  = P3V3
  25  IO25  BI  = P3V3_STBY
  26  IO26  BI  = GND
  27  IO27  BI  = PU_PCH_TLS_ENABLE_STRAP
  28  IO28  BI  = FM_PE_SLOTX24_WAKE_N
  29  IO29  BI  = RST_PCIE_RISER1_PERST_R_N
  30  IO30  BI  = SMB_HOST_STBY_LVC3_SDA_R5
  31  IO31  BI  = GND
  32  IO32  BI  = SMB_HOST_STBY_LVC3_SCL_R5
  33  IO33  BI  = CLK_100M_PCH_SLOTX24_S5_DP
  34  IO34  BI  = GND
  35  IO35  BI  = CLK_100M_PCH_SLOTX24_S5_DN
  36  IO36  BI  = CLK_100M_PCH_SLOTX24_S4_DP
  37  IO37  BI  = GND
  38  IO38  BI  = CLK_100M_PCH_SLOTX24_S4_DN
  39  IO39  BI  = CLK_100M_PCH_SLOTX24_S0_DP
  40  IO40  BI  = GND
  41  IO41  BI  = CLK_100M_PCH_SLOTX24_S0_DN
  42  IO42  BI  = CLK_100M_PCH_SLOTX24_S1_DP
  43  IO43  BI  = GND
  44  IO44  BI  = CLK_100M_PCH_SLOTX24_S1_DN
  45  IO45  BI  = CLK_100M_PCH_SLOTX24_S3_DP
  46  IO46  BI  = GND
  47  IO47  BI  = CLK_100M_PCH_SLOTX24_S3_DN
  48  IO48  BI  = CLK_100M_PCH_SLOTX24_S2_DP
  49  IO49  BI  = GND
  50  IO50  BI  = CLK_100M_PCH_SLOTX24_S2_DN
  51  IO51  BI  = P3E_CPU0_PE1_PCH_CON_TXN<15>
  52  IO52  BI  = GND
  53  IO53  BI  = P3E_CPU0_PE1_PCH_CON_TXP<15>
  54  IO54  BI  = P3E_CPU0_PE1_PCH_CON_RXN<15>
  55  IO55  BI  = GND
  56  IO56  BI  = P3E_CPU0_PE1_PCH_CON_RXP<15>
  57  IO57  BI  = P3E_CPU0_PE1_PCH_CON_TXP<14>
  58  IO58  BI  = GND
  59  IO59  BI  = P3E_CPU0_PE1_PCH_CON_TXN<14>
  60  IO60  BI  = P3E_CPU0_PE1_PCH_CON_RXN<14>
  61  IO61  BI  = GND
  62  IO62  BI  = P3E_CPU0_PE1_PCH_CON_RXP<14>
  63  IO63  BI  = TP_SLOTX24_RSVD63
  64  IO64  BI  = GND
  65  IO65  BI  = GND
  66  IO66  BI  = TP_SLOTX24_RSVD66
  67  IO67  BI  = P3E_CPU0_PE1_PCH_CON_TXN<13>
  68  IO68  BI  = GND
  69  IO69  BI  = P3E_CPU0_PE1_PCH_CON_TXP<13>
  70  IO70  BI  = P3E_CPU0_PE1_PCH_CON_RXN<13>
  71  IO71  BI  = GND
  72  IO72  BI  = P3E_CPU0_PE1_PCH_CON_RXP<13>
  73  IO73  BI  = P3E_CPU0_PE1_PCH_CON_TXN<12>
  74  IO74  BI  = GND
  75  IO75  BI  = P3E_CPU0_PE1_PCH_CON_TXP<12>
  76  IO76  BI  = P3E_CPU0_PE1_PCH_CON_RXN<12>
  77  IO77  BI  = GND
  78  IO78  BI  = P3E_CPU0_PE1_PCH_CON_RXP<12>
  79  IO79  BI  = P3E_CPU0_PE1_PCH_CON_TXN<11>
  80  IO80  BI  = GND
  81  IO81  BI  = P3E_CPU0_PE1_PCH_CON_TXP<11>
  82  IO82  BI  = P3E_CPU0_PE1_PCH_CON_RXN<11>
  83  IO83  BI  = GND
  84  IO84  BI  = P3E_CPU0_PE1_PCH_CON_RXP<11>
  85  IO85  BI  = P3E_CPU0_PE1_PCH_CON_TXN<10>
  86  IO86  BI  = GND
  87  IO87  BI  = P3E_CPU0_PE1_PCH_CON_TXP<10>
  88  IO88  BI  = P3E_CPU0_PE1_PCH_CON_RXN<10>
  89  IO89  BI  = GND
  90  IO90  BI  = P3E_CPU0_PE1_PCH_CON_RXP<10>
  91  IO91  BI  = P3E_CPU0_PE1_PCH_CON_TXN<9>
  92  IO92  BI  = GND
  93  IO93  BI  = P3E_CPU0_PE1_PCH_CON_TXP<9>
  94  IO94  BI  = P3E_CPU0_PE1_PCH_CON_RXN<9>
  95  IO95  BI  = GND
  96  IO96  BI  = P3E_CPU0_PE1_PCH_CON_RXP<9>
  97  IO97  BI  = P3E_CPU0_PE1_PCH_CON_TXN<8>
  98  IO98  BI  = GND
  99  IO99  BI  = P3E_CPU0_PE1_PCH_CON_TXP<8>
  100  IO100  BI  = P3E_CPU0_PE1_PCH_CON_RXN<8>
  101  IO101  BI  = GND
  102  IO102  BI  = P3E_CPU0_PE1_PCH_CON_RXP<8>
  103  IO103  BI  = P3E_CPU0_PE1_SS_C_TXP<7>
  104  IO104  BI  = GND
  105  IO105  BI  = P3E_CPU0_PE1_SS_C_TXN<7>
  106  IO106  BI  = P3E_CPU0_PE1_SS_R_RXN<7>
  107  IO107  BI  = GND
  108  IO108  BI  = P3E_CPU0_PE1_SS_R_RXP<7>
  109  IO109  BI  = P3E_CPU0_PE1_SS_C_TXN<6>
  110  IO110  BI  = GND
  111  IO111  BI  = P3E_CPU0_PE1_SS_C_TXP<6>
  112  IO112  BI  = P3E_CPU0_PE1_SS_R_RXN<6>
  113  IO113  BI  = GND
  114  IO114  BI  = P3E_CPU0_PE1_SS_R_RXP<6>
  115  IO115  BI  = P3E_CPU0_PE1_SS_C_TXN<5>
  116  IO116  BI  = GND
  117  IO117  BI  = P3E_CPU0_PE1_SS_C_TXP<5>
  118  IO118  BI  = P3E_CPU0_PE1_SS_R_RXN<5>
  119  IO119  BI  = GND
  120  IO120  BI  = P3E_CPU0_PE1_SS_R_RXP<5>
  121  IO121  BI  = P3E_CPU0_PE1_SS_C_TXN<4>
  122  IO122  BI  = GND
  123  IO123  BI  = P3E_CPU0_PE1_SS_C_TXP<4>
  124  IO124  BI  = P3E_CPU0_PE1_SS_R_RXN<4>
  125  IO125  BI  = GND
  126  IO126  BI  = P3E_CPU0_PE1_SS_R_RXP<4>
  127  IO127  BI  = P3E_CPU0_PE1_SS_C_TXN<3>
  128  IO128  BI  = GND
  129  IO129  BI  = P3E_CPU0_PE1_SS_C_TXP<3>
  130  IO130  BI  = P3E_CPU0_PE1_SS_R_RXN<3>
  131  IO131  BI  = GND
  132  IO132  BI  = P3E_CPU0_PE1_SS_R_RXP<3>
  133  IO133  BI  = P3E_CPU0_PE1_SS_C_TXN<2>
  134  IO134  BI  = GND
  135  IO135  BI  = P3E_CPU0_PE1_SS_C_TXP<2>
  136  IO136  BI  = P3E_CPU0_PE1_SS_R_RXN<2>
  137  IO137  BI  = GND
  138  IO138  BI  = P3E_CPU0_PE1_SS_R_RXP<2>
  139  IO139  BI  = P3E_CPU0_PE1_SS_C_TXN<1>
  140  IO140  BI  = GND
  141  IO141  BI  = P3E_CPU0_PE1_SS_C_TXP<1>
  142  IO142  BI  = P3E_CPU0_PE1_SS_R_RXN<1>
  143  IO143  BI  = GND
  144  IO144  BI  = P3E_CPU0_PE1_SS_R_RXP<1>
  145  IO145  BI  = P3E_CPU0_PE1_SS_C_TXN<0>
  146  IO146  BI  = GND
  147  IO147  BI  = P3E_CPU0_PE1_SS_C_TXP<0>
  148  IO148  BI  = P3E_CPU0_PE1_SS_R_RXN<0>
  149  IO149  BI  = GND
  150  IO150  BI  = P3E_CPU0_PE1_SS_R_RXP<0>
  151  IO151  BI  = P3E_CPU0_PE2_SS_C_TXN<0>
  152  IO152  BI  = GND
  153  IO153  BI  = P3E_CPU0_PE2_SS_C_TXP<0>
  154  IO154  BI  = P3E_CPU0_PE2_SS_RXN<0>
  155  IO155  BI  = GND
  156  IO156  BI  = P3E_CPU0_PE2_SS_RXP<0>
  157  IO157  BI  = P3E_CPU0_PE2_SS_C_TXP<1>
  158  IO158  BI  = GND
  159  IO159  BI  = P3E_CPU0_PE2_SS_C_TXN<1>
  160  IO160  BI  = P3E_CPU0_PE2_SS_RXN<1>
  161  IO161  BI  = GND
  162  IO162  BI  = P3E_CPU0_PE2_SS_RXP<1>
  163  IO163  BI  = P3E_CPU0_PE2_SS_C_TXN<2>
  164  IO164  BI  = GND
  165  IO165  BI  = P3E_CPU0_PE2_SS_C_TXP<2>
  166  IO166  BI  = P3E_CPU0_PE2_SS_RXN<2>
  167  IO167  BI  = GND
  168  IO168  BI  = P3E_CPU0_PE2_SS_RXP<2>
  169  IO169  BI  = P3E_CPU0_PE2_SS_C_TXN<3>
  170  IO170  BI  = GND
  171  IO171  BI  = P3E_CPU0_PE2_SS_C_TXP<3>
  172  IO172  BI  = P3E_CPU0_PE2_SS_RXN<3>
  173  IO173  BI  = GND
  174  IO174  BI  = P3E_CPU0_PE2_SS_RXP<3>
  175  IO175  BI  = P3E_CPU0_PE2_SS_C_TXN<4>
  176  IO176  BI  = GND
  177  IO177  BI  = P3E_CPU0_PE2_SS_C_TXP<4>
  178  IO178  BI  = P3E_CPU0_PE2_SS_RXN<4>
  179  IO179  BI  = GND
  180  IO180  BI  = P3E_CPU0_PE2_SS_RXP<4>
  181  IO181  BI  = P3E_CPU0_PE2_SS_C_TXN<5>
  182  IO182  BI  = GND
  183  IO183  BI  = P3E_CPU0_PE2_SS_C_TXP<5>
  184  IO184  BI  = P3E_CPU0_PE2_SS_RXN<5>
  185  IO185  BI  = GND
  186  IO186  BI  = P3E_CPU0_PE2_SS_RXP<5>
  187  IO187  BI  = P3E_CPU0_PE2_SS_C_TXN<6>
  188  IO188  BI  = GND
  189  IO189  BI  = P3E_CPU0_PE2_SS_C_TXP<6>
  190  IO190  BI  = P3E_CPU0_PE2_SS_RXP<6>
  191  IO191  BI  = GND
  192  IO192  BI  = P3E_CPU0_PE2_SS_RXN<6>
  193  IO193  BI  = P3E_CPU0_PE2_SS_C_TXN<7>
  194  IO194  BI  = GND
  195  IO195  BI  = P3E_CPU0_PE2_SS_C_TXP<7>
  196  IO196  BI  = P3E_CPU0_PE2_SS_RXN<7>
  197  IO197  BI  = GND
  198  IO198  BI  = P3E_CPU0_PE2_SS_RXP<7>
  199  IO199  BI  = FM_PRSNT_2_6_N
  200  IO200  BI  = GND
  MH1  MH1  UNSPEC  = GND
  MH2  MH2  UNSPEC  = GND

J8G2  CONN12_C73564003  CONN  pkg PIP  page 135
  1  IO1  BI  = TP_JUMPER_BLOCK_1_1
  2  IO2  BI  = TP_JUMPER_BLOCK_1_2
  3  IO3  BI  = RST_BMC_SRST_N
  4  IO4  BI  = FM_IE_DISABLE_N
  5  IO5  BI  = GND
  6  IO6  BI  = GND
  7  IO7  BI  = TP_JUMPER_BLOCK_1_7
  8  IO8  BI  = TP_JUMPER_BLOCK_1_8
  9  IO9  BI  = FM_CPLD_UART_CH_LOCK_N
  10  IO10  BI  = FM_DIS_ADR_DLY
  11  IO11  BI  = GND
  12  IO12  BI  = GND

J9A1  CONN4_D42317002  CONN  pkg PIP  page 135
  1  IO1  BI  = GND
  2  IO2  BI  = PU_KEY_CONN_PIN2_R
  3  IO3  BI  = GND
  4  IO4  BI  = FM_PCH_SATA_RAID_KEY_R
